# TIMECARD (Time Appliance Project (Time Card)) — schematic netlist excerpt (pin names and nets, part order shuffled) for the footprints in the layout excerpt that follows; sources: Cadence DE-HDL packaged netlist, KiCad conversion of R4006-B0001-02_R01.brd

U7  AT24MAC402_SOT23_5  AT24MAC602-STUM-T  pkg SOT23_5_H039  page 16
  SCL  = EEPROM_SCL
  GND  = SG
  SDA  = PRI_EEPROM_SDA
  VCC  = XP3R3V_FPGA
  WP  = SN_EEPROM_WP

(kicad_pcb
	(version 20260206)
	(generator "pcbnew")
	(generator_version "10.0")
	(general
		(thickness 1.6)
		(legacy_teardrops no)
	)
	(paper "A4")
	(title_block
		(title "timecard-production-celestica-r4006 — R4006-B0001-02_R01.brd")
		(comment 1 "Time Appliance Project (Time Card) / footprint 598 of 1113 (U7), pads 1-5 of 5")
	)
	(layers
		(0 "F.Cu" signal "TOP")
		(4 "In1.Cu" signal "L02_GND1")
		(6 "In2.Cu" signal "L03_SIG1")
		(8 "In3.Cu" signal "L04_GND2")
		(10 "In4.Cu" signal "L05_VCC1")
		(12 "In5.Cu" signal "L06_VCC2")
		(14 "In6.Cu" signal "L07_GND3")
		(16 "In7.Cu" signal "L08_SIG2")
		(18 "In8.Cu" signal "L09_GND4")
		(2 "B.Cu" signal "BOTTOM")
		(9 "F.Adhes" user "F.Adhesive")
		(11 "B.Adhes" user "B.Adhesive")
		(13 "F.Paste" user "Package Geometry/Pastemask Top")
		(15 "B.Paste" user "Package Geometry/Pastemask Bottom")
		(5 "F.SilkS" user "Ref Des/Silkscreen Top")
		(7 "B.SilkS" user "Ref Des/Silkscreen Bottom")
		(1 "F.Mask" user "Board Geometry/Soldermask Top")
		(3 "B.Mask" user "Board Geometry/Soldermask Bottom")
		(17 "Dwgs.User" user "User.Drawings")
		(19 "Cmts.User" user "User.Comments")
		(21 "Eco1.User" user "User.Eco1")
		(23 "Eco2.User" user "User.Eco2")
		(25 "Edge.Cuts" user "Board Geometry/Outline")
		(27 "Margin" user)
		(31 "F.CrtYd" user "Package Geometry/Place Bound Top")
		(29 "B.CrtYd" user "Package Geometry/Place Bound Bottom")
		(35 "F.Fab" user "Ref Des/Assembly Top")
		(33 "B.Fab" user "Ref Des/Assembly Bottom")
	)
	(footprint ""
		(layer "F.Cu")
		(at 25.7556 -17.5514)
		(property "Reference" "U7"
			(at 0.94742 -2.52603 0)
			(unlocked yes)
			(layer "F.SilkS")
			(effects
				(font
					(size 0.7874 0.5842)
					(thickness 0.1524)
				)
			)
		)
		(property "Value" ""
			(at 0 0 0)
			(layer "F.Fab")
			(effects
				(font
					(size 1.27 1.27)
				)
			)
		)
		(property "Device Type" "AT24MAC402_SOT23_5-A221-00002-A"
			(at 0.0508 2.549906 0)
			(unlocked yes)
			(layer "F.Fab")
			(hide yes)
			(effects
				(font
					(size 0.7874 0.5842)
					(thickness 0.1524)
				)
			)
		)
		(property "User Part Number" "PARTNUM*"
			(at 0.0508 3.515106 0)
			(unlocked yes)
			(layer "Cmts.User")
			(hide yes)
			(effects
				(font
					(size 0.7874 0.5842)
					(thickness 0.1524)
				)
			)
		)
		(duplicate_pad_numbers_are_jumpers no)
		(pad "1" smd rect
			(at -1.4351 -0.94996 90)
			(size 0.508 1.1938)
			(layers "F.Cu" "F.Mask" "F.Paste")
			(net "EEPROM_SCL")
		)
		(pad "2" smd rect
			(at -1.4351 0 90)
			(size 0.508 1.1938)
			(layers "F.Cu" "F.Mask" "F.Paste")
			(net "SG")
		)
		(pad "3" smd rect
			(at -1.4351 0.94996 90)
			(size 0.508 1.1938)
			(layers "F.Cu" "F.Mask" "F.Paste")
			(net "PRI_EEPROM_SDA")
		)
		(pad "4" smd rect
			(at 1.4351 0.94996 90)
			(size 0.508 1.1938)
			(layers "F.Cu" "F.Mask" "F.Paste")
			(net "XP3R3V_FPGA")
		)
		(pad "5" smd rect
			(at 1.4351 -0.94996 90)
			(size 0.508 1.1938)
			(layers "F.Cu" "F.Mask" "F.Paste")
			(net "SN_EEPROM_WP")
		)
	)
)
